(kicad_pcb
	(version 20260206)
	(generator "pcbnew")
	(generator_version "10.0")
	(general
		(thickness 1.6)
		(legacy_teardrops no)
	)
	(paper "A4")
	(title_block
		(title "Wiwynn_Tioga_Pass_MB.brd")
		(comment 1 "Tioga Pass / footprints 2252-2252 of 4770")
	)
	(layers
		(0 "F.Cu" signal "TOP")
		(4 "In1.Cu" signal "L2GND")
		(6 "In2.Cu" signal "L3")
		(8 "In3.Cu" signal "L4GND")
		(10 "In4.Cu" signal "L5")
		(12 "In5.Cu" signal "L6GND")
		(14 "In6.Cu" signal "L7VCC")
		(16 "In7.Cu" signal "L8VCC")
		(18 "In8.Cu" signal "L9GND")
		(20 "In9.Cu" signal "L10")
		(22 "In10.Cu" signal "L11GND")
		(24 "In11.Cu" signal "L12")
		(26 "In12.Cu" signal "L13GND")
		(2 "B.Cu" signal "BOTTOM")
		(9 "F.Adhes" user "F.Adhesive")
		(11 "B.Adhes" user "B.Adhesive")
		(13 "F.Paste" user "Package Geometry/Pastemask Top")
		(15 "B.Paste" user "Package Geometry/Pastemask Bottom")
		(5 "F.SilkS" user "Ref Des/Silkscreen Top")
		(7 "B.SilkS" user "Ref Des/Silkscreen Bottom")
		(1 "F.Mask" user "Board Geometry/Soldermask Top")
		(3 "B.Mask" user "Board Geometry/Soldermask Bottom")
		(17 "Dwgs.User" user "User.Drawings")
		(19 "Cmts.User" user "User.Comments")
		(21 "Eco1.User" user "User.Eco1")
		(23 "Eco2.User" user "User.Eco2")
		(25 "Edge.Cuts" user "Board Geometry/Outline")
		(27 "Margin" user)
		(31 "F.CrtYd" user "Package Geometry/Place Bound Top")
		(29 "B.CrtYd" user "Package Geometry/Place Bound Bottom")
		(35 "F.Fab" user "Ref Des/Assembly Top")
		(33 "B.Fab" user "Ref Des/Assembly Bottom")
	)
	(footprint ""
		(layer "F.Cu")
		(at 18.161 -75.692 180)
		(property "Reference" "EU1D2"
			(at -0.127 -3.58267 0)
			(unlocked yes)
			(layer "F.SilkS")
			(effects
				(font
					(size 0.7874 0.5842)
					(thickness 0.1524)
				)
			)
		)
		(property "Value" ""
			(at 0 0 180)
			(layer "F.Fab")
			(effects
				(font
					(size 1.27 1.27)
				)
			)
		)
		(duplicate_pad_numbers_are_jumpers no)
		(fp_line
			(start 2.9591 2.9591)
			(end -2.9591 2.9591)
			(stroke
				(width 0.1524)
				(type default)
			)
			(layer "F.SilkS")
		)
		(fp_line
			(start 2.9591 -2.9591)
			(end 2.9591 2.9591)
			(stroke
				(width 0.1524)
				(type default)
			)
			(layer "F.SilkS")
		)
		(fp_line
			(start 2.55016 2.55016)
			(end 2.257552 2.55016)
			(stroke
				(width 0.1524)
				(type default)
			)
			(layer "F.SilkS")
		)
		(fp_line
			(start 2.55016 2.257552)
			(end 2.55016 2.55016)
			(stroke
				(width 0.1524)
				(type default)
			)
			(layer "F.SilkS")
		)
		(fp_line
			(start 2.55016 -2.257552)
			(end 2.549652 -2.257552)
			(stroke
				(width 0.1524)
				(type default)
			)
			(layer "F.SilkS")
		)
		(fp_line
			(start 2.55016 -2.55016)
			(end 2.55016 -2.257552)
			(stroke
				(width 0.1524)
				(type default)
			)
			(layer "F.SilkS")
		)
		(fp_line
			(start 2.257552 2.55016)
			(end 2.257552 2.549652)
			(stroke
				(width 0.1524)
				(type default)
			)
			(layer "F.SilkS")
		)
		(fp_line
			(start 2.257552 -2.55016)
			(end 2.55016 -2.55016)
			(stroke
				(width 0.1524)
				(type default)
			)
			(layer "F.SilkS")
		)
		(fp_line
			(start -2.257552 2.55016)
			(end -2.55016 2.55016)
			(stroke
				(width 0.1524)
				(type default)
			)
			(layer "F.SilkS")
		)
		(fp_line
			(start -2.257552 -2.55016)
			(end -2.257552 -2.549652)
			(stroke
				(width 0.1524)
				(type default)
			)
			(layer "F.SilkS")
		)
		(fp_line
			(start -2.55016 2.55016)
			(end -2.55016 2.257552)
			(stroke
				(width 0.1524)
				(type default)
			)
			(layer "F.SilkS")
		)
		(fp_line
			(start -2.55016 2.257552)
			(end -2.549652 2.257552)
			(stroke
				(width 0.1524)
				(type default)
			)
			(layer "F.SilkS")
		)
		(fp_line
			(start -2.55016 -2.257552)
			(end -2.55016 -2.55016)
			(stroke
				(width 0.1524)
				(type default)
			)
			(layer "F.SilkS")
		)
		(fp_line
			(start -2.55016 -2.55016)
			(end -2.257552 -2.55016)
			(stroke
				(width 0.1524)
				(type default)
			)
			(layer "F.SilkS")
		)
		(fp_line
			(start -2.9591 2.9591)
			(end -2.9591 -2.9591)
			(stroke
				(width 0.1524)
				(type default)
			)
			(layer "F.SilkS")
		)
		(fp_line
			(start -2.9591 -2.9591)
			(end 2.9591 -2.9591)
			(stroke
				(width 0.1524)
				(type default)
			)
			(layer "F.SilkS")
		)
		(fp_circle
			(center -3.344926 -1.694942)
			(end -3.471926 -1.694942)
			(stroke
				(width 0.254)
				(type default)
			)
			(fill no)
			(layer "F.SilkS")
		)
		(fp_poly
			(pts
				(xy -2.9591 -2.9591) (xy -2.9591 -2.1209) (xy -2.1209 -2.9591)
			)
			(stroke
				(width 0)
				(type default)
			)
			(fill yes)
			(layer "F.SilkS")
		)
		(fp_poly
			(pts
				(xy -1.651 1.651) (xy 1.651 1.651) (xy 1.651 -1.651) (xy -1.651 -1.651)
			)
			(stroke
				(width 0)
				(type default)
			)
			(fill yes)
			(layer "F.Paste")
		)
		(fp_poly
			(pts
				(xy -2.55016 2.55016) (xy 2.55016 2.55016) (xy 2.55016 -2.55016) (xy -2.55016 -2.55016)
			)
			(stroke
				(width 0)
				(type default)
			)
			(fill no)
			(layer "F.CrtYd")
		)
		(fp_line
			(start 2.55016 2.55016)
			(end -2.55016 2.55016)
			(stroke
				(width 0.1)
				(type default)
			)
			(layer "F.Fab")
		)
		(fp_line
			(start 2.55016 -2.55016)
			(end 2.55016 2.55016)
			(stroke
				(width 0.1)
				(type default)
			)
			(layer "F.Fab")
		)
		(fp_line
			(start -2.55016 2.55016)
			(end -2.55016 -2.55016)
			(stroke
				(width 0.1)
				(type default)
			)
			(layer "F.Fab")
		)
		(fp_line
			(start -2.55016 -2.55016)
			(end 2.55016 -2.55016)
			(stroke
				(width 0.1)
				(type default)
			)
			(layer "F.Fab")
		)
		(fp_circle
			(center -3.309366 -2.156714)
			(end -3.436366 -2.156714)
			(stroke
				(width 0.254)
				(type default)
			)
			(fill no)
			(layer "F.Fab")
		)
		(pad "1" smd custom
			(at -2.3495 -1.75133 180)
			(size 0.0762 0.0762)
			(layers "F.Cu" "F.Mask" "F.Paste")
			(net "A_HSC_PSET")
			(options
				(clearance outline)
				(anchor circle)
			)
			(primitives
				(gr_poly
					(pts
						(xy -0.3556 0.1524) (xy -0.3556 -0.1524)
						(arc
							(start 0.2032 -0.1524)
							(mid 0.3556 0)
							(end 0.2032 0.1524)
						)
					)
					(width 0)
					(fill yes)
				)
			)
		)
		(pad "2" smd custom
			(at -2.3495 -1.25095 180)
			(size 0.0762 0.0762)
			(layers "F.Cu" "F.Mask" "F.Paste")
			(net "A_HSC_VCAP")
			(options
				(clearance outline)
				(anchor circle)
			)
			(primitives
				(gr_poly
					(pts
						(xy -0.3556 0.1524) (xy -0.3556 -0.1524)
						(arc
							(start 0.2032 -0.1524)
							(mid 0.3556 0)
							(end 0.2032 0.1524)
						)
					)
					(width 0)
					(fill yes)
				)
			)
		)
		(pad "3" smd custom
			(at -2.3495 -0.75057 180)
			(size 0.0762 0.0762)
			(layers "F.Cu" "F.Mask" "F.Paste")
			(net "A_HSC_ISET")
			(options
				(clearance outline)
				(anchor circle)
			)
			(primitives
				(gr_poly
					(pts
						(xy -0.3556 0.1524) (xy -0.3556 -0.1524)
						(arc
							(start 0.2032 -0.1524)
							(mid 0.3556 0)
							(end 0.2032 0.1524)
						)
					)
					(width 0)
					(fill yes)
				)
			)
		)
		(pad "4" smd custom
			(at -2.3495 -0.25019 180)
			(size 0.0762 0.0762)
			(layers "F.Cu" "F.Mask" "F.Paste")
			(net "A_HSC_ISTART")
			(options
				(clearance outline)
				(anchor circle)
			)
			(primitives
				(gr_poly
					(pts
						(xy -0.3556 0.1524) (xy -0.3556 -0.1524)
						(arc
							(start 0.2032 -0.1524)
							(mid 0.3556 0)
							(end 0.2032 0.1524)
						)
					)
					(width 0)
					(fill yes)
				)
			)
		)
		(pad "5" smd custom
			(at -2.3495 0.25019 180)
			(size 0.0762 0.0762)
			(layers "F.Cu" "F.Mask" "F.Paste")
			(net "A_HSC_TIMER")
			(options
				(clearance outline)
				(anchor circle)
			)
			(primitives
				(gr_poly
					(pts
						(xy -0.3556 0.1524) (xy -0.3556 -0.1524)
						(arc
							(start 0.2032 -0.1524)
							(mid 0.3556 0)
							(end 0.2032 0.1524)
						)
					)
					(width 0)
					(fill yes)
				)
			)
		)
		(pad "6" smd custom
			(at -2.3495 0.75057 180)
			(size 0.0762 0.0762)
			(layers "F.Cu" "F.Mask" "F.Paste")
			(net "IRQ_HSC_FAULT_R_N")
			(options
				(clearance outline)
				(anchor circle)
			)
			(primitives
				(gr_poly
					(pts
						(xy -0.3556 0.1524) (xy -0.3556 -0.1524)
						(arc
							(start 0.2032 -0.1524)
							(mid 0.3556 0)
							(end 0.2032 0.1524)
						)
					)
					(width 0)
					(fill yes)
				)
			)
		)
		(pad "7" smd custom
			(at -2.3495 1.25095 180)
			(size 0.0762 0.0762)
			(layers "F.Cu" "F.Mask" "F.Paste")
			(net "FM_P12V_HSC_ADR1")
			(options
				(clearance outline)
				(anchor circle)
			)
			(primitives
				(gr_poly
					(pts
						(xy -0.3556 0.1524) (xy -0.3556 -0.1524)
						(arc
							(start 0.2032 -0.1524)
							(mid 0.3556 0)
							(end 0.2032 0.1524)
						)
					)
					(width 0)
					(fill yes)
				)
			)
		)
		(pad "8" smd custom
			(at -2.3495 1.75133 180)
			(size 0.0762 0.0762)
			(layers "F.Cu" "F.Mask" "F.Paste")
			(net "FM_P12V_HSC_ADR2")
			(options
				(clearance outline)
				(anchor circle)
			)
			(primitives
				(gr_poly
					(pts
						(xy -0.3556 0.1524) (xy -0.3556 -0.1524)
						(arc
							(start 0.2032 -0.1524)
							(mid 0.3556 0)
							(end 0.2032 0.1524)
						)
					)
					(width 0)
					(fill yes)
				)
			)
		)
		(pad "9" smd custom
			(at -1.75133 2.3495 180)
			(size 0.0762 0.0762)
			(layers "F.Cu" "F.Mask" "F.Paste")
			(net "TP_HSC_SPISSN")
			(options
				(clearance outline)
				(anchor circle)
			)
			(primitives
				(gr_poly
					(pts
						(xy 0.1524 0.3556) (xy -0.1524 0.3556)
						(arc
							(start -0.1524 -0.2032)
							(mid 0 -0.3556)
							(end 0.1524 -0.2032)
						)
					)
					(width 0)
					(fill yes)
				)
			)
		)
		(pad "10" smd custom
			(at -1.25095 2.3495 180)
			(size 0.0762 0.0762)
			(layers "F.Cu" "F.Mask" "F.Paste")
			(net "TP_HSC_MCLK")
			(options
				(clearance outline)
				(anchor circle)
			)
			(primitives
				(gr_poly
					(pts
						(xy 0.1524 0.3556) (xy -0.1524 0.3556)
						(arc
							(start -0.1524 -0.2032)
							(mid 0 -0.3556)
							(end 0.1524 -0.2032)
						)
					)
					(width 0)
					(fill yes)
				)
			)
		)
		(pad "11" smd custom
			(at -0.75057 2.3495 180)
			(size 0.0762 0.0762)
			(layers "F.Cu" "F.Mask" "F.Paste")
			(net "TP_HSC_MDAT")
			(options
				(clearance outline)
				(anchor circle)
			)
			(primitives
				(gr_poly
					(pts
						(xy 0.1524 0.3556) (xy -0.1524 0.3556)
						(arc
							(start -0.1524 -0.2032)
							(mid 0 -0.3556)
							(end 0.1524 -0.2032)
						)
					)
					(width 0)
					(fill yes)
				)
			)
		)
		(pad "12" smd custom
			(at -0.25019 2.3495 180)
			(size 0.0762 0.0762)
			(layers "F.Cu" "F.Mask" "F.Paste")
			(net "FM_P12V_HOTSWAP0_EN")
			(options
				(clearance outline)
				(anchor circle)
			)
			(primitives
				(gr_poly
					(pts
						(xy 0.1524 0.3556) (xy -0.1524 0.3556)
						(arc
							(start -0.1524 -0.2032)
							(mid 0 -0.3556)
							(end 0.1524 -0.2032)
						)
					)
					(width 0)
					(fill yes)
				)
			)
		)
		(pad "13" smd custom
			(at 0.25019 2.3495 180)
			(size 0.0762 0.0762)
			(layers "F.Cu" "F.Mask" "F.Paste")
			(net "IRQ_SML1_PMBUS_ALERT_R_N")
			(options
				(clearance outline)
				(anchor circle)
			)
			(primitives
				(gr_poly
					(pts
						(xy 0.1524 0.3556) (xy -0.1524 0.3556)
						(arc
							(start -0.1524 -0.2032)
							(mid 0 -0.3556)
							(end 0.1524 -0.2032)
						)
					)
					(width 0)
					(fill yes)
				)
			)
		)
		(pad "14" smd custom
			(at 0.75057 2.3495 180)
			(size 0.0762 0.0762)
			(layers "F.Cu" "F.Mask" "F.Paste")
			(net "TP_HSC_ALERT2_N")
			(options
				(clearance outline)
				(anchor circle)
			)
			(primitives
				(gr_poly
					(pts
						(xy 0.1524 0.3556) (xy -0.1524 0.3556)
						(arc
							(start -0.1524 -0.2032)
							(mid 0 -0.3556)
							(end 0.1524 -0.2032)
						)
					)
					(width 0)
					(fill yes)
				)
			)
		)
		(pad "15" smd custom
			(at 1.25095 2.3495 180)
			(size 0.0762 0.0762)
			(layers "F.Cu" "F.Mask" "F.Paste")
			(net "SMB_3V3SB_HSC_SDA_R")
			(options
				(clearance outline)
				(anchor circle)
			)
			(primitives
				(gr_poly
					(pts
						(xy 0.1524 0.3556) (xy -0.1524 0.3556)
						(arc
							(start -0.1524 -0.2032)
							(mid 0 -0.3556)
							(end 0.1524 -0.2032)
						)
					)
					(width 0)
					(fill yes)
				)
			)
		)
		(pad "16" smd custom
			(at 1.75133 2.3495 180)
			(size 0.0762 0.0762)
			(layers "F.Cu" "F.Mask" "F.Paste")
			(net "SMB_3V3SB_HSC_SCL_R")
			(options
				(clearance outline)
				(anchor circle)
			)
			(primitives
				(gr_poly
					(pts
						(xy 0.1524 0.3556) (xy -0.1524 0.3556)
						(arc
							(start -0.1524 -0.2032)
							(mid 0 -0.3556)
							(end 0.1524 -0.2032)
						)
					)
					(width 0)
					(fill yes)
				)
			)
		)
		(pad "17" smd custom
			(at 2.3495 1.75133 180)
			(size 0.0762 0.0762)
			(layers "F.Cu" "F.Mask" "F.Paste")
			(net "PD_HSC_RETRY_N")
			(options
				(clearance outline)
				(anchor circle)
			)
			(primitives
				(gr_poly
					(pts
						(xy 0.3556 -0.1524) (xy 0.3556 0.1524)
						(arc
							(start -0.2032 0.1524)
							(mid -0.3556 0)
							(end -0.2032 -0.1524)
						)
					)
					(width 0)
					(fill yes)
				)
			)
		)
		(pad "18" smd custom
			(at 2.3495 1.25095 180)
			(size 0.0762 0.0762)
			(layers "F.Cu" "F.Mask" "F.Paste")
			(net "PWRGD_P12V_R")
			(options
				(clearance outline)
				(anchor circle)
			)
			(primitives
				(gr_poly
					(pts
						(xy 0.3556 -0.1524) (xy 0.3556 0.1524)
						(arc
							(start -0.2032 0.1524)
							(mid -0.3556 0)
							(end -0.2032 -0.1524)
						)
					)
					(width 0)
					(fill yes)
				)
			)
		)
		(pad "19" smd custom
			(at 2.3495 0.75057 180)
			(size 0.0762 0.0762)
			(layers "F.Cu" "F.Mask" "F.Paste")
			(net "A_HSC_CSOUT")
			(options
				(clearance outline)
				(anchor circle)
			)
			(primitives
				(gr_poly
					(pts
						(xy 0.3556 -0.1524) (xy 0.3556 0.1524)
						(arc
							(start -0.2032 0.1524)
							(mid -0.3556 0)
							(end -0.2032 -0.1524)
						)
					)
					(width 0)
					(fill yes)
				)
			)
		)
		(pad "20" smd custom
			(at 2.3495 0.25019 180)
			(size 0.0762 0.0762)
			(layers "F.Cu" "F.Mask" "F.Paste")
			(net "A_HSC_VOUT")
			(options
				(clearance outline)
				(anchor circle)
			)
			(primitives
				(gr_poly
					(pts
						(xy 0.3556 -0.1524) (xy 0.3556 0.1524)
						(arc
							(start -0.2032 0.1524)
							(mid -0.3556 0)
							(end -0.2032 -0.1524)
						)
					)
					(width 0)
					(fill yes)
				)
			)
		)
		(pad "21" smd custom
			(at 2.3495 -0.25019 180)
			(size 0.0762 0.0762)
			(layers "F.Cu" "F.Mask" "F.Paste")
			(net "A_HSC_PWGIN")
			(options
				(clearance outline)
				(anchor circle)
			)
			(primitives
				(gr_poly
					(pts
						(xy 0.3556 -0.1524) (xy 0.3556 0.1524)
						(arc
							(start -0.2032 0.1524)
							(mid -0.3556 0)
							(end -0.2032 -0.1524)
						)
					)
					(width 0)
					(fill yes)
				)
			)
		)
		(pad "22" smd custom
			(at 2.3495 -0.75057 180)
			(size 0.0762 0.0762)
			(layers "F.Cu" "F.Mask" "F.Paste")
			(net "AGND_HSC")
			(options
				(clearance outline)
				(anchor circle)
			)
			(primitives
				(gr_poly
					(pts
						(xy 0.3556 -0.1524) (xy 0.3556 0.1524)
						(arc
							(start -0.2032 0.1524)
							(mid -0.3556 0)
							(end -0.2032 -0.1524)
						)
					)
					(width 0)
					(fill yes)
				)
			)
		)
		(pad "23" smd custom
			(at 2.3495 -1.25095 180)
			(size 0.0762 0.0762)
			(layers "F.Cu" "F.Mask" "F.Paste")
			(net "GND")
			(options
				(clearance outline)
				(anchor circle)
			)
			(primitives
				(gr_poly
					(pts
						(xy 0.3556 -0.1524) (xy 0.3556 0.1524)
						(arc
							(start -0.2032 0.1524)
							(mid -0.3556 0)
							(end -0.2032 -0.1524)
						)
					)
					(width 0)
					(fill yes)
				)
			)
		)
		(pad "24" smd custom
			(at 2.3495 -1.75133 180)
			(size 0.0762 0.0762)
			(layers "F.Cu" "F.Mask" "F.Paste")
			(net "A_HSC_GATE")
			(options
				(clearance outline)
				(anchor circle)
			)
			(primitives
				(gr_poly
					(pts
						(xy 0.3556 -0.1524) (xy 0.3556 0.1524)
						(arc
							(start -0.2032 0.1524)
							(mid -0.3556 0)
							(end -0.2032 -0.1524)
						)
					)
					(width 0)
					(fill yes)
				)
			)
		)
		(pad "25" smd custom
			(at 1.75133 -2.3495 180)
			(size 0.0762 0.0762)
			(layers "F.Cu" "F.Mask" "F.Paste")
			(net "A_HSC_TEMP")
			(options
				(clearance outline)
				(anchor circle)
			)
			(primitives
				(gr_poly
					(pts
						(xy -0.1524 -0.3556) (xy 0.1524 -0.3556)
						(arc
							(start 0.1524 0.2032)
							(mid 0 0.3556)
							(end -0.1524 0.2032)
						)
					)
					(width 0)
					(fill yes)
				)
			)
		)
		(pad "26" smd custom
			(at 1.25095 -2.3495 180)
			(size 0.0762 0.0762)
			(layers "F.Cu" "F.Mask" "F.Paste")
			(net "A_HSC_MON")
			(options
				(clearance outline)
				(anchor circle)
			)
			(primitives
				(gr_poly
					(pts
						(xy -0.1524 -0.3556) (xy 0.1524 -0.3556)
						(arc
							(start 0.1524 0.2032)
							(mid 0 0.3556)
							(end -0.1524 0.2032)
						)
					)
					(width 0)
					(fill yes)
				)
			)
		)
		(pad "27" smd custom
			(at 0.75057 -2.3495 180)
			(size 0.0762 0.0762)
			(layers "F.Cu" "F.Mask" "F.Paste")
			(net "A_HSC_HSN")
			(options
				(clearance outline)
				(anchor circle)
			)
			(primitives
				(gr_poly
					(pts
						(xy -0.1524 -0.3556) (xy 0.1524 -0.3556)
						(arc
							(start 0.1524 0.2032)
							(mid 0 0.3556)
							(end -0.1524 0.2032)
						)
					)
					(width 0)
					(fill yes)
				)
			)
		)
		(pad "28" smd custom
			(at 0.25019 -2.3495 180)
			(size 0.0762 0.0762)
			(layers "F.Cu" "F.Mask" "F.Paste")
			(net "A_HSC_HSP")
			(options
				(clearance outline)
				(anchor circle)
			)
			(primitives
				(gr_poly
					(pts
						(xy -0.1524 -0.3556) (xy 0.1524 -0.3556)
						(arc
							(start 0.1524 0.2032)
							(mid 0 0.3556)
							(end -0.1524 0.2032)
						)
					)
					(width 0)
					(fill yes)
				)
			)
		)
		(pad "29" smd custom
			(at -0.25019 -2.3495 180)
			(size 0.0762 0.0762)
			(layers "F.Cu" "F.Mask" "F.Paste")
			(net "A_HSC_MOP")
			(options
				(clearance outline)
				(anchor circle)
			)
			(primitives
				(gr_poly
					(pts
						(xy -0.1524 -0.3556) (xy 0.1524 -0.3556)
						(arc
							(start 0.1524 0.2032)
							(mid 0 0.3556)
							(end -0.1524 0.2032)
						)
					)
					(width 0)
					(fill yes)
				)
			)
		)
		(pad "30" smd custom
			(at -0.75057 -2.3495 180)
			(size 0.0762 0.0762)
			(layers "F.Cu" "F.Mask" "F.Paste")
			(net "P12V_HSC_VCC")
			(options
				(clearance outline)
				(anchor circle)
			)
			(primitives
				(gr_poly
					(pts
						(xy -0.1524 -0.3556) (xy 0.1524 -0.3556)
						(arc
							(start 0.1524 0.2032)
							(mid 0 0.3556)
							(end -0.1524 0.2032)
						)
					)
					(width 0)
					(fill yes)
				)
			)
		)
		(pad "31" smd custom
			(at -1.25095 -2.3495 180)
			(size 0.0762 0.0762)
			(layers "F.Cu" "F.Mask" "F.Paste")
			(net "A_HSC_UV")
			(options
				(clearance outline)
				(anchor circle)
			)
			(primitives
				(gr_poly
					(pts
						(xy -0.1524 -0.3556) (xy 0.1524 -0.3556)
						(arc
							(start 0.1524 0.2032)
							(mid 0 0.3556)
							(end -0.1524 0.2032)
						)
					)
					(width 0)
					(fill yes)
				)
			)
		)
		(pad "32" smd custom
			(at -1.75133 -2.3495 180)
			(size 0.0762 0.0762)
			(layers "F.Cu" "F.Mask" "F.Paste")
			(net "A_HSC_OV")
			(options
				(clearance outline)
				(anchor circle)
			)
			(primitives
				(gr_poly
					(pts
						(xy -0.1524 -0.3556) (xy 0.1524 -0.3556)
						(arc
							(start 0.1524 0.2032)
							(mid 0 0.3556)
							(end -0.1524 0.2032)
						)
					)
					(width 0)
					(fill yes)
				)
			)
		)
		(pad "33" smd rect
			(at 0 0 180)
			(size 3.302 3.302)
			(layers "F.Cu" "F.Mask" "F.Paste")
			(net "AGND_HSC")
		)
	)
)
